# T6G (Grand Teton) — schematic netlist excerpt (pin names and nets, part order shuffled) for the footprints in the layout excerpt that follows; sources: Cadence DE-HDL packaged netlist, KiCad conversion of 04192023_DAF0TMB3IC0_F0TG_MB_C_brd_V02_OCP.brd

C269  Q_CAP  10UF 6.3V 20% X6S  pkg C0402  page 323 : A = P0V9_CPU1_RT0_2A ; B = GND
R535  Q_RES  2.2K 5% CHIP  pkg 0402LF  page 54 : A = APML_CPU1_ALERT_N ; B = PVDD18_S5_P1

(kicad_pcb
	(version 20260206)
	(generator "pcbnew")
	(generator_version "10.0")
	(general
		(thickness 1.6)
		(legacy_teardrops no)
	)
	(paper "A4")
	(title_block
		(title "04192023_DAF0TMB3IC0_F0TG_MB_C_brd_V02_OCP.brd")
		(comment 1 "Grand Teton / footprints 5070-5071 of 8354")
	)
	(layers
		(0 "F.Cu" signal "TOP")
		(4 "In1.Cu" signal "GND")
		(6 "In2.Cu" signal "IN1")
		(8 "In3.Cu" signal "GND1")
		(10 "In4.Cu" signal "IN2")
		(12 "In5.Cu" signal "GND2")
		(14 "In6.Cu" signal "IN3")
		(16 "In7.Cu" signal "GND3")
		(18 "In8.Cu" signal "VCC")
		(20 "In9.Cu" signal "VCC1")
		(22 "In10.Cu" signal "GND4")
		(24 "In11.Cu" signal "IN4")
		(26 "In12.Cu" signal "GND5")
		(28 "In13.Cu" signal "IN5")
		(30 "In14.Cu" signal "GND6")
		(32 "In15.Cu" signal "IN6")
		(34 "In16.Cu" signal "GND7")
		(2 "B.Cu" signal "BOTTOM")
		(9 "F.Adhes" user "F.Adhesive")
		(11 "B.Adhes" user "B.Adhesive")
		(13 "F.Paste" user "Package Geometry/Pastemask Top")
		(15 "B.Paste" user "Package Geometry/Pastemask Bottom")
		(5 "F.SilkS" user "Ref Des/Silkscreen Top")
		(7 "B.SilkS" user "Ref Des/Silkscreen Bottom")
		(1 "F.Mask" user "Board Geometry/Soldermask Top")
		(3 "B.Mask" user "Board Geometry/Soldermask Bottom")
		(17 "Dwgs.User" user "User.Drawings")
		(19 "Cmts.User" user "User.Comments")
		(21 "Eco1.User" user "User.Eco1")
		(23 "Eco2.User" user "User.Eco2")
		(25 "Edge.Cuts" user "Board Geometry/Outline")
		(27 "Margin" user)
		(31 "F.CrtYd" user "Package Geometry/Place Bound Top")
		(29 "B.CrtYd" user "Package Geometry/Place Bound Bottom")
		(35 "F.Fab" user "Ref Des/Assembly Top")
		(33 "B.Fab" user "Ref Des/Assembly Bottom")
	)
	(footprint ""
		(layer "B.Cu")
		(at 70.172834 -202.688952)
		(property "Reference" "R535"
			(at 0 0 0)
			(layer "B.SilkS")
			(hide yes)
			(effects
				(font
					(size 1.27 1.27)
				)
				(justify mirror)
			)
		)
		(property "Value" ""
			(at 0 0 0)
			(layer "B.Fab")
			(effects
				(font
					(size 1.27 1.27)
				)
				(justify mirror)
			)
		)
		(duplicate_pad_numbers_are_jumpers no)
		(fp_line
			(start -0.7874 -0.4064)
			(end -0.7874 0.4064)
			(stroke
				(width 0.1524)
				(type default)
			)
			(layer "B.SilkS")
		)
		(fp_line
			(start -0.7874 0.4064)
			(end 0.7874 0.4064)
			(stroke
				(width 0.1524)
				(type default)
			)
			(layer "B.SilkS")
		)
		(fp_line
			(start 0.7874 -0.4064)
			(end -0.7874 -0.4064)
			(stroke
				(width 0.1524)
				(type default)
			)
			(layer "B.SilkS")
		)
		(fp_line
			(start 0.7874 0.4064)
			(end 0.7874 -0.4064)
			(stroke
				(width 0.1524)
				(type default)
			)
			(layer "B.SilkS")
		)
		(fp_line
			(start -0.67945 -0.3048)
			(end -0.67945 0.3048)
			(stroke
				(width 0.1)
				(type default)
			)
			(layer "B.Fab")
		)
		(fp_line
			(start -0.67945 0.3048)
			(end -0.120396 0.3048)
			(stroke
				(width 0.1)
				(type default)
			)
			(layer "B.Fab")
		)
		(fp_line
			(start -0.12065 -0.3048)
			(end -0.67945 -0.3048)
			(stroke
				(width 0.1)
				(type default)
			)
			(layer "B.Fab")
		)
		(fp_line
			(start -0.12065 -0.2794)
			(end -0.12065 -0.3048)
			(stroke
				(width 0.1)
				(type default)
			)
			(layer "B.Fab")
		)
		(fp_line
			(start -0.120396 0.2794)
			(end 0.12065 0.2794)
			(stroke
				(width 0.1)
				(type default)
			)
			(layer "B.Fab")
		)
		(fp_line
			(start -0.120396 0.3048)
			(end -0.120396 0.2794)
			(stroke
				(width 0.1)
				(type default)
			)
			(layer "B.Fab")
		)
		(fp_line
			(start 0.12065 -0.305054)
			(end 0.12065 -0.2794)
			(stroke
				(width 0.1)
				(type default)
			)
			(layer "B.Fab")
		)
		(fp_line
			(start 0.12065 -0.2794)
			(end -0.12065 -0.2794)
			(stroke
				(width 0.1)
				(type default)
			)
			(layer "B.Fab")
		)
		(fp_line
			(start 0.12065 0.2794)
			(end 0.12065 0.3048)
			(stroke
				(width 0.1)
				(type default)
			)
			(layer "B.Fab")
		)
		(fp_line
			(start 0.12065 0.3048)
			(end 0.67945 0.3048)
			(stroke
				(width 0.1)
				(type default)
			)
			(layer "B.Fab")
		)
		(fp_line
			(start 0.67945 -0.305054)
			(end 0.12065 -0.305054)
			(stroke
				(width 0.1)
				(type default)
			)
			(layer "B.Fab")
		)
		(fp_line
			(start 0.67945 0.3048)
			(end 0.67945 -0.305054)
			(stroke
				(width 0.1)
				(type default)
			)
			(layer "B.Fab")
		)
		(pad "1" smd circle
			(at 0.40005 0 180)
			(size 0 0)
			(layers "B.Cu" "B.Mask" "B.Paste")
			(net "APML_CPU1_ALERT_N")
		)
		(pad "2" smd circle
			(at -0.40005 0 180)
			(size 0 0)
			(layers "B.Cu" "B.Mask" "B.Paste")
			(net "PVDD18_S5_P1")
		)
	)
	(footprint ""
		(layer "B.Cu")
		(at 65.391284 -390.560052 90)
		(property "Reference" "C269"
			(at 0 0 90)
			(layer "B.SilkS")
			(hide yes)
			(effects
				(font
					(size 1.27 1.27)
				)
				(justify mirror)
			)
		)
		(property "Value" ""
			(at 0 0 90)
			(layer "B.Fab")
			(effects
				(font
					(size 1.27 1.27)
				)
				(justify mirror)
			)
		)
		(duplicate_pad_numbers_are_jumpers no)
		(fp_line
			(start 0.7874 -0.4064)
			(end -0.7874 -0.4064)
			(stroke
				(width 0.1524)
				(type default)
			)
			(layer "B.SilkS")
		)
		(fp_line
			(start -0.7874 -0.4064)
			(end -0.7874 0.4064)
			(stroke
				(width 0.1524)
				(type default)
			)
			(layer "B.SilkS")
		)
		(fp_line
			(start 0.7874 0.4064)
			(end 0.7874 -0.4064)
			(stroke
				(width 0.1524)
				(type default)
			)
			(layer "B.SilkS")
		)
		(fp_line
			(start -0.7874 0.4064)
			(end 0.7874 0.4064)
			(stroke
				(width 0.1524)
				(type default)
			)
			(layer "B.SilkS")
		)
		(fp_line
			(start 0.67945 -0.305054)
			(end 0.12065 -0.305054)
			(stroke
				(width 0.1)
				(type default)
			)
			(layer "B.Fab")
		)
		(fp_line
			(start 0.12065 -0.305054)
			(end 0.12065 -0.2794)
			(stroke
				(width 0.1)
				(type default)
			)
			(layer "B.Fab")
		)
		(fp_line
			(start -0.12065 -0.3048)
			(end -0.67945 -0.3048)
			(stroke
				(width 0.1)
				(type default)
			)
			(layer "B.Fab")
		)
		(fp_line
			(start -0.67945 -0.3048)
			(end -0.67945 0.3048)
			(stroke
				(width 0.1)
				(type default)
			)
			(layer "B.Fab")
		)
		(fp_line
			(start 0.12065 -0.2794)
			(end -0.12065 -0.2794)
			(stroke
				(width 0.1)
				(type default)
			)
			(layer "B.Fab")
		)
		(fp_line
			(start -0.12065 -0.2794)
			(end -0.12065 -0.3048)
			(stroke
				(width 0.1)
				(type default)
			)
			(layer "B.Fab")
		)
		(fp_line
			(start 0.12065 0.2794)
			(end 0.12065 0.3048)
			(stroke
				(width 0.1)
				(type default)
			)
			(layer "B.Fab")
		)
		(fp_line
			(start -0.120396 0.2794)
			(end 0.12065 0.2794)
			(stroke
				(width 0.1)
				(type default)
			)
			(layer "B.Fab")
		)
		(fp_line
			(start 0.67945 0.3048)
			(end 0.67945 -0.305054)
			(stroke
				(width 0.1)
				(type default)
			)
			(layer "B.Fab")
		)
		(fp_line
			(start 0.12065 0.3048)
			(end 0.67945 0.3048)
			(stroke
				(width 0.1)
				(type default)
			)
			(layer "B.Fab")
		)
		(fp_line
			(start -0.120396 0.3048)
			(end -0.120396 0.2794)
			(stroke
				(width 0.1)
				(type default)
			)
			(layer "B.Fab")
		)
		(fp_line
			(start -0.67945 0.3048)
			(end -0.120396 0.3048)
			(stroke
				(width 0.1)
				(type default)
			)
			(layer "B.Fab")
		)
		(pad "1" smd circle
			(at 0.40005 0 270)
			(size 0 0)
			(layers "B.Cu" "B.Mask" "B.Paste")
			(net "P0V9_CPU1_RT0_2A")
		)
		(pad "2" smd circle
			(at -0.40005 0 270)
			(size 0 0)
			(layers "B.Cu" "B.Mask" "B.Paste")
			(net "GND")
		)
	)
)
